# T6G (Grand Teton) — schematic netlist excerpt (pin names and nets, part order shuffled) for the footprints in the layout excerpt that follows; sources: Cadence DE-HDL packaged netlist, KiCad conversion of 04192023_DAF0TMB3IC0_F0TG_MB_C_brd_V02_OCP.brd

R275  Q_RES  33 5% CHIP  pkg 0402LF  page 82 : A = CLR_CMOS ; B = FM_CLR_CMOS
C2173  Q_CAP  22UF 4V 20% X6S  pkg C0402  page 69 : A = PVDDCR_CPU0_P0 ; B = GND

(kicad_pcb
	(version 20260206)
	(generator "pcbnew")
	(generator_version "10.0")
	(general
		(thickness 1.6)
		(legacy_teardrops no)
	)
	(paper "A4")
	(title_block
		(title "04192023_DAF0TMB3IC0_F0TG_MB_C_brd_V02_OCP.brd")
		(comment 1 "Grand Teton / footprints 6149-6151 of 8354")
	)
	(layers
		(0 "F.Cu" signal "TOP")
		(4 "In1.Cu" signal "GND")
		(6 "In2.Cu" signal "IN1")
		(8 "In3.Cu" signal "GND1")
		(10 "In4.Cu" signal "IN2")
		(12 "In5.Cu" signal "GND2")
		(14 "In6.Cu" signal "IN3")
		(16 "In7.Cu" signal "GND3")
		(18 "In8.Cu" signal "VCC")
		(20 "In9.Cu" signal "VCC1")
		(22 "In10.Cu" signal "GND4")
		(24 "In11.Cu" signal "IN4")
		(26 "In12.Cu" signal "GND5")
		(28 "In13.Cu" signal "IN5")
		(30 "In14.Cu" signal "GND6")
		(32 "In15.Cu" signal "IN6")
		(34 "In16.Cu" signal "GND7")
		(2 "B.Cu" signal "BOTTOM")
		(9 "F.Adhes" user "F.Adhesive")
		(11 "B.Adhes" user "B.Adhesive")
		(13 "F.Paste" user "Package Geometry/Pastemask Top")
		(15 "B.Paste" user "Package Geometry/Pastemask Bottom")
		(5 "F.SilkS" user "Ref Des/Silkscreen Top")
		(7 "B.SilkS" user "Ref Des/Silkscreen Bottom")
		(1 "F.Mask" user "Board Geometry/Soldermask Top")
		(3 "B.Mask" user "Board Geometry/Soldermask Bottom")
		(17 "Dwgs.User" user "User.Drawings")
		(19 "Cmts.User" user "User.Comments")
		(21 "Eco1.User" user "User.Eco1")
		(23 "Eco2.User" user "User.Eco2")
		(25 "Edge.Cuts" user "Board Geometry/Outline")
		(27 "Margin" user)
		(31 "F.CrtYd" user "Package Geometry/Place Bound Top")
		(29 "B.CrtYd" user "Package Geometry/Place Bound Bottom")
		(35 "F.Fab" user "Ref Des/Assembly Top")
		(33 "B.Fab" user "Ref Des/Assembly Bottom")
	)
	(footprint ""
		(layer "B.Cu")
		(at 187.871608 -100.290376 -90)
		(property "Reference" "R275"
			(at 0 0 90)
			(layer "B.SilkS")
			(hide yes)
			(effects
				(font
					(size 1.27 1.27)
				)
				(justify mirror)
			)
		)
		(property "Value" ""
			(at 0 0 90)
			(layer "B.Fab")
			(effects
				(font
					(size 1.27 1.27)
				)
				(justify mirror)
			)
		)
		(duplicate_pad_numbers_are_jumpers no)
		(fp_line
			(start -0.7874 0.4064)
			(end 0.7874 0.4064)
			(stroke
				(width 0.1524)
				(type default)
			)
			(layer "B.SilkS")
		)
		(fp_line
			(start 0.7874 0.4064)
			(end 0.7874 -0.4064)
			(stroke
				(width 0.1524)
				(type default)
			)
			(layer "B.SilkS")
		)
		(fp_line
			(start -0.7874 -0.4064)
			(end -0.7874 0.4064)
			(stroke
				(width 0.1524)
				(type default)
			)
			(layer "B.SilkS")
		)
		(fp_line
			(start 0.7874 -0.4064)
			(end -0.7874 -0.4064)
			(stroke
				(width 0.1524)
				(type default)
			)
			(layer "B.SilkS")
		)
		(fp_line
			(start -0.67945 0.3048)
			(end -0.120396 0.3048)
			(stroke
				(width 0.1)
				(type default)
			)
			(layer "B.Fab")
		)
		(fp_line
			(start -0.120396 0.3048)
			(end -0.120396 0.2794)
			(stroke
				(width 0.1)
				(type default)
			)
			(layer "B.Fab")
		)
		(fp_line
			(start 0.12065 0.3048)
			(end 0.67945 0.3048)
			(stroke
				(width 0.1)
				(type default)
			)
			(layer "B.Fab")
		)
		(fp_line
			(start 0.67945 0.3048)
			(end 0.67945 -0.305054)
			(stroke
				(width 0.1)
				(type default)
			)
			(layer "B.Fab")
		)
		(fp_line
			(start -0.120396 0.2794)
			(end 0.12065 0.2794)
			(stroke
				(width 0.1)
				(type default)
			)
			(layer "B.Fab")
		)
		(fp_line
			(start 0.12065 0.2794)
			(end 0.12065 0.3048)
			(stroke
				(width 0.1)
				(type default)
			)
			(layer "B.Fab")
		)
		(fp_line
			(start -0.12065 -0.2794)
			(end -0.12065 -0.3048)
			(stroke
				(width 0.1)
				(type default)
			)
			(layer "B.Fab")
		)
		(fp_line
			(start 0.12065 -0.2794)
			(end -0.12065 -0.2794)
			(stroke
				(width 0.1)
				(type default)
			)
			(layer "B.Fab")
		)
		(fp_line
			(start -0.67945 -0.3048)
			(end -0.67945 0.3048)
			(stroke
				(width 0.1)
				(type default)
			)
			(layer "B.Fab")
		)
		(fp_line
			(start -0.12065 -0.3048)
			(end -0.67945 -0.3048)
			(stroke
				(width 0.1)
				(type default)
			)
			(layer "B.Fab")
		)
		(fp_line
			(start 0.12065 -0.305054)
			(end 0.12065 -0.2794)
			(stroke
				(width 0.1)
				(type default)
			)
			(layer "B.Fab")
		)
		(fp_line
			(start 0.67945 -0.305054)
			(end 0.12065 -0.305054)
			(stroke
				(width 0.1)
				(type default)
			)
			(layer "B.Fab")
		)
		(pad "1" smd circle
			(at 0.40005 0 90)
			(size 0 0)
			(layers "B.Cu" "B.Mask" "B.Paste")
			(net "CLR_CMOS")
		)
		(pad "2" smd circle
			(at -0.40005 0 90)
			(size 0 0)
			(layers "B.Cu" "B.Mask" "B.Paste")
			(net "FM_CLR_CMOS")
		)
	)
	(footprint ""
		(layer "B.Cu")
		(at 367.741454 -249.36831)
		(property "Reference" "C2173"
			(at 0 0 0)
			(layer "B.SilkS")
			(hide yes)
			(effects
				(font
					(size 1.27 1.27)
				)
				(justify mirror)
			)
		)
		(property "Value" ""
			(at 0 0 0)
			(layer "B.Fab")
			(effects
				(font
					(size 1.27 1.27)
				)
				(justify mirror)
			)
		)
		(duplicate_pad_numbers_are_jumpers no)
		(fp_line
			(start -0.7874 -0.4064)
			(end -0.7874 0.4064)
			(stroke
				(width 0.1524)
				(type default)
			)
			(layer "B.SilkS")
		)
		(fp_line
			(start -0.7874 0.4064)
			(end 0.7874 0.4064)
			(stroke
				(width 0.1524)
				(type default)
			)
			(layer "B.SilkS")
		)
		(fp_line
			(start 0.7874 -0.4064)
			(end -0.7874 -0.4064)
			(stroke
				(width 0.1524)
				(type default)
			)
			(layer "B.SilkS")
		)
		(fp_line
			(start 0.7874 0.4064)
			(end 0.7874 -0.4064)
			(stroke
				(width 0.1524)
				(type default)
			)
			(layer "B.SilkS")
		)
		(fp_line
			(start -0.67945 -0.3048)
			(end -0.67945 0.3048)
			(stroke
				(width 0.1)
				(type default)
			)
			(layer "B.Fab")
		)
		(fp_line
			(start -0.67945 0.3048)
			(end -0.120396 0.3048)
			(stroke
				(width 0.1)
				(type default)
			)
			(layer "B.Fab")
		)
		(fp_line
			(start -0.12065 -0.3048)
			(end -0.67945 -0.3048)
			(stroke
				(width 0.1)
				(type default)
			)
			(layer "B.Fab")
		)
		(fp_line
			(start -0.12065 -0.2794)
			(end -0.12065 -0.3048)
			(stroke
				(width 0.1)
				(type default)
			)
			(layer "B.Fab")
		)
		(fp_line
			(start -0.120396 0.2794)
			(end 0.12065 0.2794)
			(stroke
				(width 0.1)
				(type default)
			)
			(layer "B.Fab")
		)
		(fp_line
			(start -0.120396 0.3048)
			(end -0.120396 0.2794)
			(stroke
				(width 0.1)
				(type default)
			)
			(layer "B.Fab")
		)
		(fp_line
			(start 0.12065 -0.305054)
			(end 0.12065 -0.2794)
			(stroke
				(width 0.1)
				(type default)
			)
			(layer "B.Fab")
		)
		(fp_line
			(start 0.12065 -0.2794)
			(end -0.12065 -0.2794)
			(stroke
				(width 0.1)
				(type default)
			)
			(layer "B.Fab")
		)
		(fp_line
			(start 0.12065 0.2794)
			(end 0.12065 0.3048)
			(stroke
				(width 0.1)
				(type default)
			)
			(layer "B.Fab")
		)
		(fp_line
			(start 0.12065 0.3048)
			(end 0.67945 0.3048)
			(stroke
				(width 0.1)
				(type default)
			)
			(layer "B.Fab")
		)
		(fp_line
			(start 0.67945 -0.305054)
			(end 0.12065 -0.305054)
			(stroke
				(width 0.1)
				(type default)
			)
			(layer "B.Fab")
		)
		(fp_line
			(start 0.67945 0.3048)
			(end 0.67945 -0.305054)
			(stroke
				(width 0.1)
				(type default)
			)
			(layer "B.Fab")
		)
		(pad "1" smd circle
			(at 0.40005 0 180)
			(size 0 0)
			(layers "B.Cu" "B.Mask" "B.Paste")
			(net "PVDDCR_CPU0_P0")
		)
		(pad "2" smd circle
			(at -0.40005 0 180)
			(size 0 0)
			(layers "B.Cu" "B.Mask" "B.Paste")
			(net "GND")
		)
	)
	(footprint ""
		(layer "B.Cu")
		(at 398.473168 -45.272706 180)
		(property "Reference" ""
			(at 0 0 0)
			(layer "B.SilkS")
			(hide yes)
			(effects
				(font
					(size 1.27 1.27)
				)
				(justify mirror)
			)
		)
		(property "Value" ""
			(at 0 0 0)
			(layer "B.Fab")
			(effects
				(font
					(size 1.27 1.27)
				)
				(justify mirror)
			)
		)
		(duplicate_pad_numbers_are_jumpers no)
		(pad "1" smd circle
			(at 0 0)
			(size 0.9906 0.9906)
			(layers "B.Cu" "B.Mask" "B.Paste")
			(net "Net_2234")
		)
		(zone
			(layer "B.Cu")
			(hatch none 0.5)
			(connect_pads
				(clearance 0)
			)
			(min_thickness 0.25)
			(keepout
				(tracks not_allowed)
				(vias allowed)
				(pads allowed)
				(copperpour not_allowed)
				(footprints allowed)
			)
			(placement
				(enabled no)
				(sheetname "")
			)
			(fill
				(thermal_gap 0.5)
				(thermal_bridge_width 0.5)
				(island_removal_mode 0)
			)
			(polygon
				(pts
					(arc
						(start 400.098768 -45.272706)
						(mid 396.847568 -45.272706)
						(end 400.098768 -45.272706)
					)
				)
			)
		)
	)
)
